# T6G (Grand Teton) — schematic netlist excerpt (pin names and nets, part order shuffled) for the footprints in the layout excerpt that follows; sources: Cadence DE-HDL packaged netlist, KiCad conversion of 04192023_DAF0TMB3IC0_F0TG_MB_C_brd_V02_OCP.brd

R259  Q_RES  33 5% CHIP  pkg 0402LF  page 226 : A = PWRGD_PVDD18_S5_P1 ; B = PWRGD_PVDD18_S5_R_P1
C6515  Q_CAP_DIFFBUS  DIFF BUS_0.22UF 6.3V 20% X6S  pkg C0201  page 275 : \1\ = P5E_CPU0_P0_TX_BUF_C_DP<7> ; \2\ = P5E_CPU0_P0_TX_BUF_DP<7>
R4574  Q_RES  0 5% EMPTY  pkg 0402LF  page 125 : A = PRSNT_CABLE_GPU_A1_N ; B = PRSNT_CABLE_GPU_A1_ISO_N

(kicad_pcb
	(version 20260206)
	(generator "pcbnew")
	(generator_version "10.0")
	(general
		(thickness 1.6)
		(legacy_teardrops no)
	)
	(paper "A4")
	(title_block
		(title "04192023_DAF0TMB3IC0_F0TG_MB_C_brd_V02_OCP.brd")
		(comment 1 "Grand Teton / footprints 1708-1710 of 8354")
	)
	(layers
		(0 "F.Cu" signal "TOP")
		(4 "In1.Cu" signal "GND")
		(6 "In2.Cu" signal "IN1")
		(8 "In3.Cu" signal "GND1")
		(10 "In4.Cu" signal "IN2")
		(12 "In5.Cu" signal "GND2")
		(14 "In6.Cu" signal "IN3")
		(16 "In7.Cu" signal "GND3")
		(18 "In8.Cu" signal "VCC")
		(20 "In9.Cu" signal "VCC1")
		(22 "In10.Cu" signal "GND4")
		(24 "In11.Cu" signal "IN4")
		(26 "In12.Cu" signal "GND5")
		(28 "In13.Cu" signal "IN5")
		(30 "In14.Cu" signal "GND6")
		(32 "In15.Cu" signal "IN6")
		(34 "In16.Cu" signal "GND7")
		(2 "B.Cu" signal "BOTTOM")
		(9 "F.Adhes" user "F.Adhesive")
		(11 "B.Adhes" user "B.Adhesive")
		(13 "F.Paste" user "Package Geometry/Pastemask Top")
		(15 "B.Paste" user "Package Geometry/Pastemask Bottom")
		(5 "F.SilkS" user "Ref Des/Silkscreen Top")
		(7 "B.SilkS" user "Ref Des/Silkscreen Bottom")
		(1 "F.Mask" user "Board Geometry/Soldermask Top")
		(3 "B.Mask" user "Board Geometry/Soldermask Bottom")
		(17 "Dwgs.User" user "User.Drawings")
		(19 "Cmts.User" user "User.Comments")
		(21 "Eco1.User" user "User.Eco1")
		(23 "Eco2.User" user "User.Eco2")
		(25 "Edge.Cuts" user "Board Geometry/Outline")
		(27 "Margin" user)
		(31 "F.CrtYd" user "Package Geometry/Place Bound Top")
		(29 "B.CrtYd" user "Package Geometry/Place Bound Bottom")
		(35 "F.Fab" user "Ref Des/Assembly Top")
		(33 "B.Fab" user "Ref Des/Assembly Bottom")
	)
	(footprint ""
		(layer "F.Cu")
		(at 356.484682 -414.062418)
		(property "Reference" "R4574"
			(at 0 0 0)
			(layer "F.SilkS")
			(hide yes)
			(effects
				(font
					(size 1.27 1.27)
				)
			)
		)
		(property "Value" ""
			(at 0 0 0)
			(layer "F.Fab")
			(effects
				(font
					(size 1.27 1.27)
				)
			)
		)
		(duplicate_pad_numbers_are_jumpers no)
		(fp_line
			(start -0.7874 -0.4064)
			(end 0.7874 -0.4064)
			(stroke
				(width 0.1524)
				(type default)
			)
			(layer "F.SilkS")
		)
		(fp_line
			(start -0.7874 0.4064)
			(end -0.7874 -0.4064)
			(stroke
				(width 0.1524)
				(type default)
			)
			(layer "F.SilkS")
		)
		(fp_line
			(start 0.7874 -0.4064)
			(end 0.7874 0.4064)
			(stroke
				(width 0.1524)
				(type default)
			)
			(layer "F.SilkS")
		)
		(fp_line
			(start 0.7874 0.4064)
			(end -0.7874 0.4064)
			(stroke
				(width 0.1524)
				(type default)
			)
			(layer "F.SilkS")
		)
		(fp_line
			(start -0.67945 -0.305054)
			(end -0.12065 -0.305054)
			(stroke
				(width 0.1)
				(type default)
			)
			(layer "F.Fab")
		)
		(fp_line
			(start -0.67945 0.3048)
			(end -0.67945 -0.305054)
			(stroke
				(width 0.1)
				(type default)
			)
			(layer "F.Fab")
		)
		(fp_line
			(start -0.12065 -0.305054)
			(end -0.12065 -0.2794)
			(stroke
				(width 0.1)
				(type default)
			)
			(layer "F.Fab")
		)
		(fp_line
			(start -0.12065 -0.2794)
			(end 0.12065 -0.2794)
			(stroke
				(width 0.1)
				(type default)
			)
			(layer "F.Fab")
		)
		(fp_line
			(start -0.12065 0.2794)
			(end -0.12065 0.3048)
			(stroke
				(width 0.1)
				(type default)
			)
			(layer "F.Fab")
		)
		(fp_line
			(start -0.12065 0.3048)
			(end -0.67945 0.3048)
			(stroke
				(width 0.1)
				(type default)
			)
			(layer "F.Fab")
		)
		(fp_line
			(start 0.120396 0.2794)
			(end -0.12065 0.2794)
			(stroke
				(width 0.1)
				(type default)
			)
			(layer "F.Fab")
		)
		(fp_line
			(start 0.120396 0.3048)
			(end 0.120396 0.2794)
			(stroke
				(width 0.1)
				(type default)
			)
			(layer "F.Fab")
		)
		(fp_line
			(start 0.12065 -0.3048)
			(end 0.67945 -0.3048)
			(stroke
				(width 0.1)
				(type default)
			)
			(layer "F.Fab")
		)
		(fp_line
			(start 0.12065 -0.2794)
			(end 0.12065 -0.3048)
			(stroke
				(width 0.1)
				(type default)
			)
			(layer "F.Fab")
		)
		(fp_line
			(start 0.67945 -0.3048)
			(end 0.67945 0.3048)
			(stroke
				(width 0.1)
				(type default)
			)
			(layer "F.Fab")
		)
		(fp_line
			(start 0.67945 0.3048)
			(end 0.120396 0.3048)
			(stroke
				(width 0.1)
				(type default)
			)
			(layer "F.Fab")
		)
		(pad "1" smd circle
			(at -0.40005 0)
			(size 0 0)
			(layers "F.Cu" "F.Mask" "F.Paste")
			(net "PRSNT_CABLE_GPU_A1_N")
		)
		(pad "2" smd circle
			(at 0.40005 0)
			(size 0 0)
			(layers "F.Cu" "F.Mask" "F.Paste")
			(net "PRSNT_CABLE_GPU_A1_ISO_N")
		)
	)
	(footprint ""
		(layer "F.Cu")
		(at 205.24089 -108.545376 180)
		(property "Reference" "R259"
			(at 0 0 180)
			(layer "F.SilkS")
			(hide yes)
			(effects
				(font
					(size 1.27 1.27)
				)
			)
		)
		(property "Value" ""
			(at 0 0 180)
			(layer "F.Fab")
			(effects
				(font
					(size 1.27 1.27)
				)
			)
		)
		(duplicate_pad_numbers_are_jumpers no)
		(fp_line
			(start 0.7874 0.4064)
			(end -0.7874 0.4064)
			(stroke
				(width 0.1524)
				(type default)
			)
			(layer "F.SilkS")
		)
		(fp_line
			(start 0.7874 -0.4064)
			(end 0.7874 0.4064)
			(stroke
				(width 0.1524)
				(type default)
			)
			(layer "F.SilkS")
		)
		(fp_line
			(start -0.7874 0.4064)
			(end -0.7874 -0.4064)
			(stroke
				(width 0.1524)
				(type default)
			)
			(layer "F.SilkS")
		)
		(fp_line
			(start -0.7874 -0.4064)
			(end 0.7874 -0.4064)
			(stroke
				(width 0.1524)
				(type default)
			)
			(layer "F.SilkS")
		)
		(fp_line
			(start 0.67945 0.3048)
			(end 0.120396 0.3048)
			(stroke
				(width 0.1)
				(type default)
			)
			(layer "F.Fab")
		)
		(fp_line
			(start 0.67945 -0.3048)
			(end 0.67945 0.3048)
			(stroke
				(width 0.1)
				(type default)
			)
			(layer "F.Fab")
		)
		(fp_line
			(start 0.12065 -0.2794)
			(end 0.12065 -0.3048)
			(stroke
				(width 0.1)
				(type default)
			)
			(layer "F.Fab")
		)
		(fp_line
			(start 0.12065 -0.3048)
			(end 0.67945 -0.3048)
			(stroke
				(width 0.1)
				(type default)
			)
			(layer "F.Fab")
		)
		(fp_line
			(start 0.120396 0.3048)
			(end 0.120396 0.2794)
			(stroke
				(width 0.1)
				(type default)
			)
			(layer "F.Fab")
		)
		(fp_line
			(start 0.120396 0.2794)
			(end -0.12065 0.2794)
			(stroke
				(width 0.1)
				(type default)
			)
			(layer "F.Fab")
		)
		(fp_line
			(start -0.12065 0.3048)
			(end -0.67945 0.3048)
			(stroke
				(width 0.1)
				(type default)
			)
			(layer "F.Fab")
		)
		(fp_line
			(start -0.12065 0.2794)
			(end -0.12065 0.3048)
			(stroke
				(width 0.1)
				(type default)
			)
			(layer "F.Fab")
		)
		(fp_line
			(start -0.12065 -0.2794)
			(end 0.12065 -0.2794)
			(stroke
				(width 0.1)
				(type default)
			)
			(layer "F.Fab")
		)
		(fp_line
			(start -0.12065 -0.305054)
			(end -0.12065 -0.2794)
			(stroke
				(width 0.1)
				(type default)
			)
			(layer "F.Fab")
		)
		(fp_line
			(start -0.67945 0.3048)
			(end -0.67945 -0.305054)
			(stroke
				(width 0.1)
				(type default)
			)
			(layer "F.Fab")
		)
		(fp_line
			(start -0.67945 -0.305054)
			(end -0.12065 -0.305054)
			(stroke
				(width 0.1)
				(type default)
			)
			(layer "F.Fab")
		)
		(pad "1" smd circle
			(at -0.40005 0 180)
			(size 0 0)
			(layers "F.Cu" "F.Mask" "F.Paste")
			(net "PWRGD_PVDD18_S5_P1")
		)
		(pad "2" smd circle
			(at 0.40005 0 180)
			(size 0 0)
			(layers "F.Cu" "F.Mask" "F.Paste")
			(net "PWRGD_PVDD18_S5_R_P1")
		)
	)
	(footprint ""
		(layer "F.Cu")
		(at 326.125586 -416.899344 -90)
		(property "Reference" "C6515"
			(at 0 0 270)
			(layer "F.SilkS")
			(hide yes)
			(effects
				(font
					(size 1.27 1.27)
				)
			)
		)
		(property "Value" ""
			(at 0 0 270)
			(layer "F.Fab")
			(effects
				(font
					(size 1.27 1.27)
				)
			)
		)
		(duplicate_pad_numbers_are_jumpers no)
		(fp_line
			(start -0.299974 0.150114)
			(end -0.299974 -0.150114)
			(stroke
				(width 0.1)
				(type default)
			)
			(layer "F.Fab")
		)
		(fp_line
			(start 0.299974 0.150114)
			(end -0.299974 0.150114)
			(stroke
				(width 0.1)
				(type default)
			)
			(layer "F.Fab")
		)
		(fp_line
			(start -0.299974 -0.150114)
			(end 0.299974 -0.150114)
			(stroke
				(width 0.1)
				(type default)
			)
			(layer "F.Fab")
		)
		(fp_line
			(start 0.299974 -0.150114)
			(end 0.299974 0.150114)
			(stroke
				(width 0.1)
				(type default)
			)
			(layer "F.Fab")
		)
		(pad "1" smd rect
			(at -0.2667 0 270)
			(size 0.3048 0.381)
			(layers "F.Cu" "F.Mask" "F.Paste")
			(net "P5E_CPU0_P0_TX_BUF_C_DP<7>")
		)
		(pad "2" smd rect
			(at 0.2667 0 270)
			(size 0.3048 0.381)
			(layers "F.Cu" "F.Mask" "F.Paste")
			(net "P5E_CPU0_P0_TX_BUF_DP<7>")
		)
	)
)
